(kicad_pcb
	(version 20221018)
	(generator pcbnew)
	(general
    (thickness 1.7403)
  )
	(paper "A4")
	(title_block
    (title "Data Center RDIMM DDR4 Tester")
    (date "2024-09-30")
    (rev "1.2.4")
		(comment 9 "footprints 629-637 of 690")
	)
	(layers
    (0 "F.Cu" signal)
    (1 "In1.Cu" power)
    (2 "In2.Cu" signal)
    (3 "In3.Cu" power)
    (4 "In4.Cu" power)
    (5 "In5.Cu" signal)
    (6 "In6.Cu" power)
    (7 "In7.Cu" signal)
    (8 "In8.Cu" power)
    (9 "In9.Cu" signal)
    (10 "In10.Cu" power)
    (31 "B.Cu" signal)
    (32 "B.Adhes" user "B.Adhesive")
    (33 "F.Adhes" user "F.Adhesive")
    (34 "B.Paste" user)
    (35 "F.Paste" user)
    (36 "B.SilkS" user "B.Silkscreen")
    (37 "F.SilkS" user "F.Silkscreen")
    (38 "B.Mask" user)
    (39 "F.Mask" user)
    (40 "Dwgs.User" user "User.Drawings")
    (41 "Cmts.User" user "User.Comments")
    (42 "Eco1.User" user "User.Eco1")
    (43 "Eco2.User" user "User.Eco2")
    (44 "Edge.Cuts" user)
    (45 "Margin" user)
    (46 "B.CrtYd" user "B.Courtyard")
    (47 "F.CrtYd" user "F.Courtyard")
    (48 "B.Fab" user)
    (49 "F.Fab" user)
  )
	(footprint "data-center-rdimm-ddr4-tester-footprints:R_0603_1608Metric" (layer "B.Cu")
    (at 186.62 83.32)
    (descr "Resistor SMD 0603")
    (tags "resistor SMD 0603")
    (property "Author" "Antmicro")
    (property "License" "Apache-2.0")
    (property "MPN" "CR0603-FX-80R6ELF")
    (property "Manufacturer" "Bourns")
    (property "Sheetfile" "fpga-banks-16-34.kicad_sch")
    (property "Sheetname" "FPGA banks 16-34")
    (property "Tolerance" "1%")
    (property "Val" "80R6")
    (property "ki_description" "80R6 resistor in 0603 package with 1% tolerance")
    (attr smd)
    (fp_text reference "R64" (at -0.91 0.36 180) (layer "B.SilkS")
        (effects (font (size 0.7 0.7) (thickness 0.15)) (justify left bottom mirror))
    )
    (fp_text value "R_80R6_0603" (at 0 -1.6 180) (layer "B.Fab") hide
        (effects (font (size 0.7 0.7) (thickness 0.15)) (justify left bottom mirror))
    )
    (fp_text user "${REFERENCE}" (at -1.25 -3.898 180) (layer "B.Fab") hide
        (effects (font (size 0.7 0.7) (thickness 0.15)) (justify left bottom mirror))
    )
    (fp_text user "Author: Antmicro" (at -1.25 -4.9 180) (layer "B.Fab") hide
        (effects (font (size 0.7 0.7) (thickness 0.15)) (justify left bottom mirror))
    )
    (fp_text user "License: Apache-2.0" (at -1.25 -5.9 180) (layer "B.Fab") hide
        (effects (font (size 0.7 0.7) (thickness 0.15)) (justify left bottom mirror))
    )
    (fp_line (start -0.3 -0.3) (end 0.3 -0.3)
      (stroke (width 0.15) (type solid)) (layer "B.SilkS"))
    (fp_line (start -0.3 0.3) (end 0.3 0.3)
      (stroke (width 0.15) (type solid)) (layer "B.SilkS"))
    (fp_rect (start -1.25 0.7) (end 1.25 -0.7)
      (stroke (width 0.05) (type solid)) (fill none) (layer "B.CrtYd"))
    (fp_rect (start -0.8 0.4) (end 0.8 -0.4)
      (stroke (width 0.15) (type solid)) (fill none) (layer "B.Fab"))
    (pad "1" smd roundrect (at -0.7 0) (size 0.6 0.8) (layers "B.Cu" "B.Paste" "B.Mask") (roundrect_rratio 0.2)
      (net 310 "VRP") (pintype "passive"))
    (pad "2" smd roundrect (at 0.7 0) (size 0.6 0.8) (layers "B.Cu" "B.Paste" "B.Mask") (roundrect_rratio 0.2)
      (net 9 "GND") (pintype "passive"))
  )
	(footprint "data-center-rdimm-ddr4-tester-footprints:C_0402_1005Metric" (layer "B.Cu")
    (at 135.11 97.37)
    (descr "Capacitor SMD 0402")
    (tags "capacitor SMD 0402")
    (property "Author" "Antmicro")
    (property "Dielectric" "X5R")
    (property "License" "Apache-2.0")
    (property "MPN" "GRM155R61H104KE14D")
    (property "Manufacturer" "Murata")
    (property "Sheetfile" "supply.kicad_sch")
    (property "Sheetname" "Supply")
    (property "Val" "100n")
    (property "Voltage" "50V")
    (property "ki_description" " ")
    (attr smd)
    (fp_text reference "C275" (at 1.44 -0.54 180) (layer "B.SilkS")
        (effects (font (size 0.7 0.7) (thickness 0.15)) (justify left bottom mirror))
    )
    (fp_text value "C_100n_0402" (at 0 -1.4 180) (layer "B.Fab") hide
        (effects (font (size 0.7 0.7) (thickness 0.15)) (justify left bottom mirror))
    )
    (fp_text user "Author: Antmicro" (at -0.932 -4.17 180) (layer "B.Fab") hide
        (effects (font (size 0.7 0.7) (thickness 0.15)) (justify left bottom mirror))
    )
    (fp_text user "License: Apache-2.0" (at -0.932 -5.17 180) (layer "B.Fab") hide
        (effects (font (size 0.7 0.7) (thickness 0.15)) (justify left bottom mirror))
    )
    (fp_text user "${REFERENCE}" (at -0.932 -3.168 180) (layer "B.Fab") hide
        (effects (font (size 0.7 0.7) (thickness 0.15)) (justify left bottom mirror))
    )
    (fp_rect (start -0.94 0.47) (end 0.94 -0.47)
      (stroke (width 0.05) (type solid)) (fill none) (layer "B.CrtYd"))
    (fp_rect (start -0.499 0.249) (end 0.499 -0.249)
      (stroke (width 0.15) (type solid)) (fill none) (layer "B.Fab"))
    (pad "1" smd roundrect (at -0.484 0) (size 0.59 0.64) (layers "B.Cu" "B.Paste" "B.Mask") (roundrect_rratio 0.25)
      (net 307 "5V0_SYS") (pintype "passive"))
    (pad "2" smd roundrect (at 0.484 0) (size 0.59 0.64) (layers "B.Cu" "B.Paste" "B.Mask") (roundrect_rratio 0.25)
      (net 9 "GND") (pintype "passive"))
  )
	(footprint "data-center-rdimm-ddr4-tester-footprints:C_1206_3216Metric" (layer "B.Cu")
    (at 193.5 114.03 180)
    (descr "Capacitor SMD 1206")
    (tags "capacitor SMD 1206")
    (property "Author" "Antmicro")
    (property "Dielectric" "")
    (property "License" "Apache-2.0")
    (property "MPN" "C3216X5R1C476M160AB")
    (property "Manufacturer" "TDK")
    (property "Sheetfile" "ethernet.kicad_sch")
    (property "Sheetname" "Ethernet")
    (property "Val" "47u/16V")
    (property "Voltage" "")
    (property "ki_description" " ")
    (attr smd)
    (fp_text reference "C227" (at -1.46 -2.07) (layer "B.SilkS")
        (effects (font (size 0.7 0.7) (thickness 0.15)) (justify left bottom mirror))
    )
    (fp_text value "C_47u_16V_1206" (at 0 -2.1) (layer "B.Fab") hide
        (effects (font (size 0.7 0.7) (thickness 0.15)) (justify left bottom mirror))
    )
    (fp_text user "License: Apache-2.0" (at -2.8 -6.6) (layer "B.Fab") hide
        (effects (font (size 0.7 0.7) (thickness 0.15)) (justify left bottom mirror))
    )
    (fp_text user "Author: Antmicro" (at -2.8 -5.6) (layer "B.Fab") hide
        (effects (font (size 0.7 0.7) (thickness 0.15)) (justify left bottom mirror))
    )
    (fp_text user "${REFERENCE}" (at -2.8 -4.6) (layer "B.Fab") hide
        (effects (font (size 0.7 0.7) (thickness 0.15)) (justify left bottom mirror))
    )
    (fp_line (start -2.625 0.3) (end -2.625 -0.3)
      (stroke (width 0.15) (type solid)) (layer "B.SilkS"))
    (fp_line (start 0.5 -0.9) (end -0.5 -0.9)
      (stroke (width 0.15) (type solid)) (layer "B.SilkS"))
    (fp_line (start 0.5 0.9) (end -0.5 0.9)
      (stroke (width 0.15) (type solid)) (layer "B.SilkS"))
    (fp_line (start 2.625 0.3) (end 2.625 -0.3)
      (stroke (width 0.15) (type solid)) (layer "B.SilkS"))
    (fp_rect (start -2.8 1.15) (end 2.8 -1.15)
      (stroke (width 0.05) (type solid)) (fill none) (layer "B.CrtYd"))
    (fp_rect (start -1.6 0.8) (end 1.6 -0.8)
      (stroke (width 0.15) (type solid)) (fill none) (layer "B.Fab"))
    (pad "1" smd rect (at -1.8 0 180) (size 1.5 1.8) (layers "B.Cu" "B.Paste" "B.Mask")
      (net 864 "VIN_POE") (pintype "passive"))
    (pad "2" smd rect (at 1.8 0 180) (size 1.5 1.8) (layers "B.Cu" "B.Paste" "B.Mask")
      (net 9 "GND") (pintype "passive"))
  )
	(footprint "data-center-rdimm-ddr4-tester-footprints:R_0402_1005Metric" (layer "B.Cu")
    (at 185.65 127.4 180)
    (descr "Resistor SMD 0402")
    (tags "resistor SMD 0402")
    (property "Author" "Antmicro")
    (property "License" "Apache-2.0")
    (property "MPN" "CR0402-FX-4992GLF")
    (property "Manufacturer" "Bourns")
    (property "Sheetfile" "ethernet.kicad_sch")
    (property "Sheetname" "Ethernet")
    (property "Tolerance" "1%")
    (property "Val" "49k9")
    (property "ki_description" "49k9 resistor in 0402 package with 1% tolerance")
    (attr smd)
    (fp_text reference "R159" (at -3.78 -0.37) (layer "B.SilkS")
        (effects (font (size 0.7 0.7) (thickness 0.15)) (justify left bottom mirror))
    )
    (fp_text value "R_49k9_0402" (at 0 -1.4) (layer "B.Fab") hide
        (effects (font (size 0.7 0.7) (thickness 0.15)) (justify left bottom mirror))
    )
    (fp_text user "Author: Antmicro" (at -0.95 -4.169) (layer "B.Fab") hide
        (effects (font (size 0.7 0.7) (thickness 0.15)) (justify left bottom mirror))
    )
    (fp_text user "License: Apache-2.0" (at -0.95 -5.169) (layer "B.Fab") hide
        (effects (font (size 0.7 0.7) (thickness 0.15)) (justify left bottom mirror))
    )
    (fp_text user "${REFERENCE}" (at -0.95 -3.168) (layer "B.Fab") hide
        (effects (font (size 0.7 0.7) (thickness 0.15)) (justify left bottom mirror))
    )
    (fp_rect (start -0.93 0.47) (end 0.93 -0.47)
      (stroke (width 0.05) (type solid)) (fill none) (layer "B.CrtYd"))
    (fp_rect (start -0.5 0.25) (end 0.5 -0.25)
      (stroke (width 0.15) (type solid)) (fill none) (layer "B.Fab"))
    (pad "1" smd roundrect (at -0.485 0 180) (size 0.59 0.64) (layers "B.Cu" "B.Paste" "B.Mask") (roundrect_rratio 0.25)
      (net 381 "/Ethernet/VSS") (pintype "passive"))
    (pad "2" smd roundrect (at 0.485 0 180) (size 0.59 0.64) (layers "B.Cu" "B.Paste" "B.Mask") (roundrect_rratio 0.25)
      (net 617 "/Ethernet/REF") (pintype "passive"))
  )
	(footprint "data-center-rdimm-ddr4-tester-footprints:C_0201" (layer "B.Cu")
    (at 179.925 83.05 90)
    (descr "Capacitor SMD 0201")
    (tags "capacitor SMD 0201")
    (property "Author" "Antmicro")
    (property "Dielectric" "")
    (property "License" "Apache-2.0")
    (property "MPN" "CC0201KRX6S5BB104")
    (property "Manufacturer" "Yaego")
    (property "Sheetfile" "fpga-power.kicad_sch")
    (property "Sheetname" "FPGA power")
    (property "Val" "100n")
    (property "Voltage" "")
    (property "ki_description" " ")
    (attr smd)
    (fp_text reference "C278" (at 1.09 -0.465 270) (layer "B.SilkS")
        (effects (font (size 0.7 0.7) (thickness 0.15)) (justify left bottom mirror))
    )
    (fp_text value "C_100n_0201" (at 0 -1.4 270) (layer "B.Fab") hide
        (effects (font (size 0.7 0.7) (thickness 0.15)) (justify left bottom mirror))
    )
    (fp_text user "Author: Antmicro" (at -0.72 -5.4 270) (layer "B.Fab") hide
        (effects (font (size 0.7 0.7) (thickness 0.15)) (justify left bottom mirror))
    )
    (fp_text user "${REFERENCE}" (at -0.72 -3.4 270) (layer "B.Fab") hide
        (effects (font (size 0.7 0.7) (thickness 0.15)) (justify left bottom mirror))
    )
    (fp_text user "License: Apache-2.0" (at -0.72 -4.4 270) (layer "B.Fab") hide
        (effects (font (size 0.7 0.7) (thickness 0.15)) (justify left bottom mirror))
    )
    (fp_rect (start -0.72 0.38) (end 0.72 -0.38)
      (stroke (width 0.05) (type solid)) (fill none) (layer "B.CrtYd"))
    (fp_rect (start 0.3 -0.15) (end -0.301 0.149)
      (stroke (width 0.15) (type solid)) (fill none) (layer "B.Fab"))
    (pad "" smd roundrect (at -0.349 0.002 90) (size 0.318 0.36) (layers "B.Paste") (roundrect_rratio 0.25))
    (pad "" smd roundrect (at 0.341 0.002 90) (size 0.318 0.36) (layers "B.Paste") (roundrect_rratio 0.25))
    (pad "1" smd roundrect (at -0.321 0.002 90) (size 0.46 0.4) (layers "B.Cu" "B.Mask") (roundrect_rratio 0.25)
      (net 77 "VDDQ") (pintype "passive"))
    (pad "2" smd roundrect (at 0.32 0.002 90) (size 0.46 0.4) (layers "B.Cu" "B.Mask") (roundrect_rratio 0.25)
      (net 9 "GND") (pintype "passive"))
  )
	(footprint "data-center-rdimm-ddr4-tester-footprints:C_0402_1005Metric" (layer "B.Cu")
    (at 133.5 119.3 180)
    (descr "Capacitor SMD 0402")
    (tags "capacitor SMD 0402")
    (property "Author" "Antmicro")
    (property "Dielectric" "")
    (property "License" "Apache-2.0")
    (property "MPN" "C1005X6S1A105K050BC")
    (property "Manufacturer" "TDK")
    (property "Sheetfile" "interfaces.kicad_sch")
    (property "Sheetname" "Interfaces")
    (property "Val" "1u")
    (property "Voltage" "")
    (property "ki_description" " ")
    (attr smd)
    (fp_text reference "C10" (at -1.13 0.55) (layer "B.SilkS")
        (effects (font (size 0.7 0.7) (thickness 0.15)) (justify left bottom mirror))
    )
    (fp_text value "C_1u_0402" (at 0 -1.4) (layer "B.Fab") hide
        (effects (font (size 0.7 0.7) (thickness 0.15)) (justify left bottom mirror))
    )
    (fp_text user "${REFERENCE}" (at -0.932 -3.168) (layer "B.Fab") hide
        (effects (font (size 0.7 0.7) (thickness 0.15)) (justify left bottom mirror))
    )
    (fp_text user "Author: Antmicro" (at -0.932 -4.17) (layer "B.Fab") hide
        (effects (font (size 0.7 0.7) (thickness 0.15)) (justify left bottom mirror))
    )
    (fp_text user "License: Apache-2.0" (at -0.932 -5.17) (layer "B.Fab") hide
        (effects (font (size 0.7 0.7) (thickness 0.15)) (justify left bottom mirror))
    )
    (fp_rect (start -0.94 0.47) (end 0.94 -0.47)
      (stroke (width 0.05) (type solid)) (fill none) (layer "B.CrtYd"))
    (fp_rect (start -0.499 0.249) (end 0.499 -0.249)
      (stroke (width 0.15) (type solid)) (fill none) (layer "B.Fab"))
    (pad "1" smd roundrect (at -0.484 0 180) (size 0.59 0.64) (layers "B.Cu" "B.Paste" "B.Mask") (roundrect_rratio 0.25)
      (net 143 "3V3_SYS") (pintype "passive"))
    (pad "2" smd roundrect (at 0.484 0 180) (size 0.59 0.64) (layers "B.Cu" "B.Paste" "B.Mask") (roundrect_rratio 0.25)
      (net 9 "GND") (pintype "passive"))
  )
	(footprint "data-center-rdimm-ddr4-tester-footprints:C_0603_1608Metric" (layer "B.Cu")
    (at 182 78.975)
    (descr "Capacitor SMD 0603")
    (tags "capacitor 0603")
    (property "Author" "Antmicro")
    (property "Dielectric" "")
    (property "License" "Apache-2.0")
    (property "MPN" "GRM188R60J476ME15D")
    (property "Manufacturer" "Murata")
    (property "Sheetfile" "fpga-power.kicad_sch")
    (property "Sheetname" "FPGA power")
    (property "Val" "47u")
    (property "Voltage" "")
    (property "ki_description" " ")
    (attr smd)
    (fp_text reference "C81" (at 0.12 1.285 180) (layer "B.SilkS")
        (effects (font (size 0.7 0.7) (thickness 0.15)) (justify left bottom mirror))
    )
    (fp_text value "C_47u_0603" (at 0 -1.6 180) (layer "B.Fab") hide
        (effects (font (size 0.7 0.7) (thickness 0.15)) (justify left bottom mirror))
    )
    (fp_text user "Author: Antmicro" (at -1.682 -4.894 180) (layer "B.Fab") hide
        (effects (font (size 0.7 0.7) (thickness 0.15)) (justify left bottom mirror))
    )
    (fp_text user "License: Apache-2.0" (at -1.682 -5.895 180) (layer "B.Fab") hide
        (effects (font (size 0.7 0.7) (thickness 0.15)) (justify left bottom mirror))
    )
    (fp_text user "${REFERENCE}" (at -1.682 -3.895 180) (layer "B.Fab") hide
        (effects (font (size 0.7 0.7) (thickness 0.15)) (justify left bottom mirror))
    )
    (fp_line (start -0.3 -0.3) (end 0.3 -0.3)
      (stroke (width 0.15) (type solid)) (layer "B.SilkS"))
    (fp_line (start -0.3 0.3) (end 0.3 0.3)
      (stroke (width 0.15) (type solid)) (layer "B.SilkS"))
    (fp_rect (start -1.24 0.7) (end 1.24 -0.7)
      (stroke (width 0.05) (type solid)) (fill none) (layer "B.CrtYd"))
    (fp_rect (start -0.8 0.4) (end 0.8 -0.4)
      (stroke (width 0.15) (type solid)) (fill none) (layer "B.Fab"))
    (pad "1" smd roundrect (at -0.7 0) (size 0.6 0.8) (layers "B.Cu" "B.Paste" "B.Mask") (roundrect_rratio 0.2)
      (net 77 "VDDQ") (pintype "passive"))
    (pad "2" smd roundrect (at 0.7 0) (size 0.6 0.8) (layers "B.Cu" "B.Paste" "B.Mask") (roundrect_rratio 0.2)
      (net 9 "GND") (pintype "passive"))
  )
	(footprint "data-center-rdimm-ddr4-tester-footprints:C_0201" (layer "B.Cu")
    (at 180.65 95.575)
    (descr "Capacitor SMD 0201")
    (tags "capacitor SMD 0201")
    (property "Author" "Antmicro")
    (property "Dielectric" "")
    (property "License" "Apache-2.0")
    (property "MPN" "CC0201KRX6S5BB104")
    (property "Manufacturer" "Yaego")
    (property "Sheetfile" "fpga-power.kicad_sch")
    (property "Sheetname" "FPGA power")
    (property "Val" "100n")
    (property "Voltage" "")
    (property "ki_description" " ")
    (attr smd)
    (fp_text reference "C309" (at 3.46 0.265 180) (layer "B.SilkS")
        (effects (font (size 0.7 0.7) (thickness 0.15)) (justify left bottom mirror))
    )
    (fp_text value "C_100n_0201" (at 0 -1.4 180) (layer "B.Fab") hide
        (effects (font (size 0.7 0.7) (thickness 0.15)) (justify left bottom mirror))
    )
    (fp_text user "${REFERENCE}" (at -0.72 -3.4 180) (layer "B.Fab") hide
        (effects (font (size 0.7 0.7) (thickness 0.15)) (justify left bottom mirror))
    )
    (fp_text user "Author: Antmicro" (at -0.72 -5.4 180) (layer "B.Fab") hide
        (effects (font (size 0.7 0.7) (thickness 0.15)) (justify left bottom mirror))
    )
    (fp_text user "License: Apache-2.0" (at -0.72 -4.4 180) (layer "B.Fab") hide
        (effects (font (size 0.7 0.7) (thickness 0.15)) (justify left bottom mirror))
    )
    (fp_rect (start -0.72 0.38) (end 0.72 -0.38)
      (stroke (width 0.05) (type solid)) (fill none) (layer "B.CrtYd"))
    (fp_rect (start 0.3 -0.15) (end -0.301 0.149)
      (stroke (width 0.15) (type solid)) (fill none) (layer "B.Fab"))
    (pad "" smd roundrect (at -0.349 0.002) (size 0.318 0.36) (layers "B.Paste") (roundrect_rratio 0.25))
    (pad "" smd roundrect (at 0.341 0.002) (size 0.318 0.36) (layers "B.Paste") (roundrect_rratio 0.25))
    (pad "1" smd roundrect (at -0.321 0.002) (size 0.46 0.4) (layers "B.Cu" "B.Mask") (roundrect_rratio 0.25)
      (net 143 "3V3_SYS") (pintype "passive"))
    (pad "2" smd roundrect (at 0.32 0.002) (size 0.46 0.4) (layers "B.Cu" "B.Mask") (roundrect_rratio 0.25)
      (net 9 "GND") (pintype "passive"))
  )
	(footprint "data-center-rdimm-ddr4-tester-footprints:C_0201" (layer "B.Cu")
    (at 182.47 99.67)
    (descr "Capacitor SMD 0201")
    (tags "capacitor SMD 0201")
    (property "Author" "Antmicro")
    (property "Dielectric" "")
    (property "License" "Apache-2.0")
    (property "MPN" "CC0201KRX6S5BB104")
    (property "Manufacturer" "Yaego")
    (property "Sheetfile" "fpga-power.kicad_sch")
    (property "Sheetname" "FPGA power")
    (property "Val" "100n")
    (property "Voltage" "")
    (property "ki_description" " ")
    (attr smd)
    (fp_text reference "C308" (at 1.05 1.17 180) (layer "B.SilkS")
        (effects (font (size 0.7 0.7) (thickness 0.15)) (justify left bottom mirror))
    )
    (fp_text value "C_100n_0201" (at 0 -1.4 180) (layer "B.Fab") hide
        (effects (font (size 0.7 0.7) (thickness 0.15)) (justify left bottom mirror))
    )
    (fp_text user "${REFERENCE}" (at -0.72 -3.4 180) (layer "B.Fab") hide
        (effects (font (size 0.7 0.7) (thickness 0.15)) (justify left bottom mirror))
    )
    (fp_text user "Author: Antmicro" (at -0.72 -5.4 180) (layer "B.Fab") hide
        (effects (font (size 0.7 0.7) (thickness 0.15)) (justify left bottom mirror))
    )
    (fp_text user "License: Apache-2.0" (at -0.72 -4.4 180) (layer "B.Fab") hide
        (effects (font (size 0.7 0.7) (thickness 0.15)) (justify left bottom mirror))
    )
    (fp_rect (start -0.72 0.38) (end 0.72 -0.38)
      (stroke (width 0.05) (type solid)) (fill none) (layer "B.CrtYd"))
    (fp_rect (start 0.3 -0.15) (end -0.301 0.149)
      (stroke (width 0.15) (type solid)) (fill none) (layer "B.Fab"))
    (pad "" smd roundrect (at -0.349 0.002) (size 0.318 0.36) (layers "B.Paste") (roundrect_rratio 0.25))
    (pad "" smd roundrect (at 0.341 0.002) (size 0.318 0.36) (layers "B.Paste") (roundrect_rratio 0.25))
    (pad "1" smd roundrect (at -0.321 0.002) (size 0.46 0.4) (layers "B.Cu" "B.Mask") (roundrect_rratio 0.25)
      (net 143 "3V3_SYS") (pintype "passive"))
    (pad "2" smd roundrect (at 0.32 0.002) (size 0.46 0.4) (layers "B.Cu" "B.Mask") (roundrect_rratio 0.25)
      (net 9 "GND") (pintype "passive"))
  )
)
